(kicad_pcb
	(version 20241229)
	(generator "pcbnew")
	(generator_version "9.0")
	(general
		(thickness 1.62)
		(legacy_teardrops no)
	)
	(paper "A3")
	(title_block
		(title "COM Express 7 Baseboard")
		(date "2025-02-04")
		(rev "1.1.2")
		(company "Antmicro Ltd")
		(comment 1 "www.antmicro.com")
		(comment 9 "footprints 183-184 of 802")
	)
	(layers
		(0 "F.Cu" signal)
		(4 "In1.Cu" signal)
		(6 "In2.Cu" signal)
		(8 "In3.Cu" signal)
		(10 "In4.Cu" signal)
		(12 "In5.Cu" signal)
		(14 "In6.Cu" signal)
		(2 "B.Cu" signal)
		(9 "F.Adhes" user "F.Adhesive")
		(11 "B.Adhes" user "B.Adhesive")
		(13 "F.Paste" user)
		(15 "B.Paste" user)
		(5 "F.SilkS" user "F.Silkscreen")
		(7 "B.SilkS" user "B.Silkscreen")
		(1 "F.Mask" user)
		(3 "B.Mask" user)
		(17 "Dwgs.User" user "User.Drawings")
		(19 "Cmts.User" user "User.Comments")
		(21 "Eco1.User" user "User.Eco1")
		(23 "Eco2.User" user "User.Eco2")
		(25 "Edge.Cuts" user)
		(27 "Margin" user)
		(31 "F.CrtYd" user "F.Courtyard")
		(29 "B.CrtYd" user "B.Courtyard")
		(35 "F.Fab" user)
		(33 "B.Fab" user)
	)
	(footprint "antmicro-footprints:R_0402_1005Metric"
		(layer "F.Cu")
		(at 246.35 128.31 90)
		(descr "Resistor SMD 0402")
		(tags "resistor SMD 0402")
		(property "Reference" "R166"
			(at 0.8 0.45 90)
			(layer "F.SilkS")
			(effects
				(font
					(size 0.7 0.7)
					(thickness 0.15)
				)
				(justify left bottom)
			)
		)
		(property "Value" "R_1k_0402"
			(at -1.011843 1.772047 90)
			(layer "F.Fab")
			(effects
				(font
					(size 0.7 0.7)
					(thickness 0.15)
				)
				(justify left bottom)
			)
		)
		(property "Datasheet" "https://www.bourns.com/docs/product-datasheets/cr.pdf"
			(at 0 0 90)
			(layer "F.Fab")
			(hide yes)
			(effects
				(font
					(size 1.27 1.27)
					(thickness 0.15)
				)
			)
		)
		(property "Author" "Antmicro"
			(at 374.66 -118.04 0)
			(layer "F.Fab")
			(hide yes)
			(effects
				(font
					(size 1 1)
					(thickness 0.15)
				)
			)
		)
		(property "License" "Apache-2.0"
			(at 374.66 -118.04 0)
			(layer "F.Fab")
			(hide yes)
			(effects
				(font
					(size 1 1)
					(thickness 0.15)
				)
			)
		)
		(property "MPN" "CR0402-FX-1001GLF"
			(at 374.66 -118.04 0)
			(layer "F.Fab")
			(hide yes)
			(effects
				(font
					(size 1 1)
					(thickness 0.15)
				)
			)
		)
		(property "Manufacturer" "Bourns"
			(at 374.66 -118.04 0)
			(layer "F.Fab")
			(hide yes)
			(effects
				(font
					(size 1 1)
					(thickness 0.15)
				)
			)
		)
		(property "Public" "False"
			(at 374.66 -118.04 0)
			(layer "F.Fab")
			(hide yes)
			(effects
				(font
					(size 1 1)
					(thickness 0.15)
				)
			)
		)
		(property "Tolerance" "1%"
			(at 374.66 -118.04 0)
			(layer "F.Fab")
			(hide yes)
			(effects
				(font
					(size 1 1)
					(thickness 0.15)
				)
			)
		)
		(property "Val" "1k"
			(at 374.66 -118.04 0)
			(layer "F.Fab")
			(hide yes)
			(effects
				(font
					(size 1 1)
					(thickness 0.15)
				)
			)
		)
		(sheetname "Com Express 7 MGMT")
		(sheetfile "com_express_7_mgmt.kicad_sch")
		(attr smd dnp)
		(fp_rect
			(start -0.925 -0.47)
			(end 0.925 0.47)
			(stroke
				(width 0.05)
				(type default)
			)
			(fill no)
			(layer "F.CrtYd")
		)
		(fp_rect
			(start -0.5 -0.25)
			(end 0.5 0.25)
			(stroke
				(width 0.15)
				(type solid)
			)
			(fill no)
			(layer "F.Fab")
		)
		(pad "1" smd roundrect
			(at -0.48 0 90)
			(size 0.59 0.64)
			(layers "F.Cu" "F.Mask" "F.Paste")
			(roundrect_rratio 0.25)
			(net 84 "/Com Express 7 MGMT/PWRBTN")
			(pintype "passive")
			(teardrops
				(best_length_ratio 0.2)
				(max_length 1)
				(best_width_ratio 0.9)
				(max_width 2)
				(curved_edges yes)
				(filter_ratio 0.9)
				(enabled yes)
				(allow_two_segments yes)
				(prefer_zone_connections yes)
			)
		)
		(pad "2" smd roundrect
			(at 0.48 0 90)
			(size 0.59 0.64)
			(layers "F.Cu" "F.Mask" "F.Paste")
			(roundrect_rratio 0.25)
			(net 73 "+3V3_AON")
			(pintype "passive")
			(teardrops
				(best_length_ratio 0.2)
				(max_length 1)
				(best_width_ratio 0.9)
				(max_width 2)
				(curved_edges yes)
				(filter_ratio 0.9)
				(enabled yes)
				(allow_two_segments yes)
				(prefer_zone_connections yes)
			)
		)
	)
	(footprint "antmicro-footprints:R_0402_1005Metric"
		(layer "F.Cu")
		(at 143 132.88)
		(descr "Resistor SMD 0402")
		(tags "resistor SMD 0402")
		(property "Reference" "R268"
			(at -3.6 0.43 0)
			(layer "F.SilkS")
			(effects
				(font
					(size 0.7 0.7)
					(thickness 0.15)
				)
				(justify left bottom)
			)
		)
		(property "Value" "R_10k_0402"
			(at -1.011843 1.772047 0)
			(layer "F.Fab")
			(effects
				(font
					(size 0.7 0.7)
					(thickness 0.15)
				)
				(justify left bottom)
			)
		)
		(property "Datasheet" "https://www.bourns.com/docs/product-datasheets/cr.pdf"
			(at 0 0 0)
			(layer "F.Fab")
			(hide yes)
			(effects
				(font
					(size 1.27 1.27)
					(thickness 0.15)
				)
			)
		)
		(property "Author" "Antmicro"
			(at 0 0 0)
			(layer "F.Fab")
			(hide yes)
			(effects
				(font
					(size 1 1)
					(thickness 0.15)
				)
			)
		)
		(property "License" "Apache-2.0"
			(at 0 0 0)
			(layer "F.Fab")
			(hide yes)
			(effects
				(font
					(size 1 1)
					(thickness 0.15)
				)
			)
		)
		(property "MPN" "CR0402-FX-1002GLF"
			(at 0 0 0)
			(layer "F.Fab")
			(hide yes)
			(effects
				(font
					(size 1 1)
					(thickness 0.15)
				)
			)
		)
		(property "Manufacturer" "Bourns"
			(at 0 0 0)
			(layer "F.Fab")
			(hide yes)
			(effects
				(font
					(size 1 1)
					(thickness 0.15)
				)
			)
		)
		(property "Public" "False"
			(at 0 0 0)
			(layer "F.Fab")
			(hide yes)
			(effects
				(font
					(size 1 1)
					(thickness 0.15)
				)
			)
		)
		(property "Tolerance" "1%"
			(at 0 0 0)
			(layer "F.Fab")
			(hide yes)
			(effects
				(font
					(size 1 1)
					(thickness 0.15)
				)
			)
		)
		(property "Val" "10k"
			(at 0 0 0)
			(layer "F.Fab")
			(hide yes)
			(effects
				(font
					(size 1 1)
					(thickness 0.15)
				)
			)
		)
		(sheetname "KR to SFI #1")
		(sheetfile "kr_sfi.kicad_sch")
		(attr smd)
		(fp_rect
			(start -0.925 -0.47)
			(end 0.925 0.47)
			(stroke
				(width 0.05)
				(type default)
			)
			(fill no)
			(layer "F.CrtYd")
		)
		(fp_rect
			(start -0.5 -0.25)
			(end 0.5 0.25)
			(stroke
				(width 0.15)
				(type solid)
			)
			(fill no)
			(layer "F.Fab")
		)
		(pad "1" smd roundrect
			(at -0.48 0)
			(size 0.59 0.64)
			(layers "F.Cu" "F.Mask" "F.Paste")
			(roundrect_rratio 0.25)
			(net 1 "GND")
			(pintype "passive")
			(teardrops
				(best_length_ratio 0.2)
				(max_length 1)
				(best_width_ratio 0.9)
				(max_width 2)
				(curved_edges yes)
				(filter_ratio 0.9)
				(enabled yes)
				(allow_two_segments yes)
				(prefer_zone_connections yes)
			)
		)
		(pad "2" smd roundrect
			(at 0.48 0)
			(size 0.59 0.64)
			(layers "F.Cu" "F.Mask" "F.Paste")
			(roundrect_rratio 0.25)
			(net 661 "Net-(U43C-PRTAD4)")
			(pintype "passive")
			(teardrops
				(best_length_ratio 0.2)
				(max_length 1)
				(best_width_ratio 0.9)
				(max_width 2)
				(curved_edges yes)
				(filter_ratio 0.9)
				(enabled yes)
				(allow_two_segments yes)
				(prefer_zone_connections yes)
			)
		)
	)
)
